# T6G (Grand Teton) — schematic netlist excerpt (pin names and nets, part order shuffled) for the footprints in the layout excerpt that follows; sources: Cadence DE-HDL packaged netlist, KiCad conversion of 04192023_DAF0TMB3IC0_F0TG_MB_C_brd_V02_OCP.brd

C1825  Q_CAP  0.1UF 25V 10% X7R  pkg 0402  page 138 : A = P3V3_AUX ; B = GND
R8  Q_RES  100K 1% CHIP  pkg 0402LF  page 167 : A = GND ; B = JTAG_BMC_OE

(kicad_pcb
	(version 20260206)
	(generator "pcbnew")
	(generator_version "10.0")
	(general
		(thickness 1.6)
		(legacy_teardrops no)
	)
	(paper "A4")
	(title_block
		(title "04192023_DAF0TMB3IC0_F0TG_MB_C_brd_V02_OCP.brd")
		(comment 1 "Grand Teton / footprints 427-428 of 8354")
	)
	(layers
		(0 "F.Cu" signal "TOP")
		(4 "In1.Cu" signal "GND")
		(6 "In2.Cu" signal "IN1")
		(8 "In3.Cu" signal "GND1")
		(10 "In4.Cu" signal "IN2")
		(12 "In5.Cu" signal "GND2")
		(14 "In6.Cu" signal "IN3")
		(16 "In7.Cu" signal "GND3")
		(18 "In8.Cu" signal "VCC")
		(20 "In9.Cu" signal "VCC1")
		(22 "In10.Cu" signal "GND4")
		(24 "In11.Cu" signal "IN4")
		(26 "In12.Cu" signal "GND5")
		(28 "In13.Cu" signal "IN5")
		(30 "In14.Cu" signal "GND6")
		(32 "In15.Cu" signal "IN6")
		(34 "In16.Cu" signal "GND7")
		(2 "B.Cu" signal "BOTTOM")
		(9 "F.Adhes" user "F.Adhesive")
		(11 "B.Adhes" user "B.Adhesive")
		(13 "F.Paste" user "Package Geometry/Pastemask Top")
		(15 "B.Paste" user "Package Geometry/Pastemask Bottom")
		(5 "F.SilkS" user "Ref Des/Silkscreen Top")
		(7 "B.SilkS" user "Ref Des/Silkscreen Bottom")
		(1 "F.Mask" user "Board Geometry/Soldermask Top")
		(3 "B.Mask" user "Board Geometry/Soldermask Bottom")
		(17 "Dwgs.User" user "User.Drawings")
		(19 "Cmts.User" user "User.Comments")
		(21 "Eco1.User" user "User.Eco1")
		(23 "Eco2.User" user "User.Eco2")
		(25 "Edge.Cuts" user "Board Geometry/Outline")
		(27 "Margin" user)
		(31 "F.CrtYd" user "Package Geometry/Place Bound Top")
		(29 "B.CrtYd" user "Package Geometry/Place Bound Bottom")
		(35 "F.Fab" user "Ref Des/Assembly Top")
		(33 "B.Fab" user "Ref Des/Assembly Bottom")
	)
	(footprint ""
		(layer "F.Cu")
		(at 147.199096 -66.337434)
		(property "Reference" "R8"
			(at 0 0 0)
			(layer "F.SilkS")
			(hide yes)
			(effects
				(font
					(size 1.27 1.27)
				)
			)
		)
		(property "Value" ""
			(at 0 0 0)
			(layer "F.Fab")
			(effects
				(font
					(size 1.27 1.27)
				)
			)
		)
		(duplicate_pad_numbers_are_jumpers no)
		(fp_line
			(start -0.7874 -0.4064)
			(end 0.7874 -0.4064)
			(stroke
				(width 0.1524)
				(type default)
			)
			(layer "F.SilkS")
		)
		(fp_line
			(start -0.7874 0.4064)
			(end -0.7874 -0.4064)
			(stroke
				(width 0.1524)
				(type default)
			)
			(layer "F.SilkS")
		)
		(fp_line
			(start 0.7874 -0.4064)
			(end 0.7874 0.4064)
			(stroke
				(width 0.1524)
				(type default)
			)
			(layer "F.SilkS")
		)
		(fp_line
			(start 0.7874 0.4064)
			(end -0.7874 0.4064)
			(stroke
				(width 0.1524)
				(type default)
			)
			(layer "F.SilkS")
		)
		(fp_line
			(start -0.67945 -0.305054)
			(end -0.12065 -0.305054)
			(stroke
				(width 0.1)
				(type default)
			)
			(layer "F.Fab")
		)
		(fp_line
			(start -0.67945 0.3048)
			(end -0.67945 -0.305054)
			(stroke
				(width 0.1)
				(type default)
			)
			(layer "F.Fab")
		)
		(fp_line
			(start -0.12065 -0.305054)
			(end -0.12065 -0.2794)
			(stroke
				(width 0.1)
				(type default)
			)
			(layer "F.Fab")
		)
		(fp_line
			(start -0.12065 -0.2794)
			(end 0.12065 -0.2794)
			(stroke
				(width 0.1)
				(type default)
			)
			(layer "F.Fab")
		)
		(fp_line
			(start -0.12065 0.2794)
			(end -0.12065 0.3048)
			(stroke
				(width 0.1)
				(type default)
			)
			(layer "F.Fab")
		)
		(fp_line
			(start -0.12065 0.3048)
			(end -0.67945 0.3048)
			(stroke
				(width 0.1)
				(type default)
			)
			(layer "F.Fab")
		)
		(fp_line
			(start 0.120396 0.2794)
			(end -0.12065 0.2794)
			(stroke
				(width 0.1)
				(type default)
			)
			(layer "F.Fab")
		)
		(fp_line
			(start 0.120396 0.3048)
			(end 0.120396 0.2794)
			(stroke
				(width 0.1)
				(type default)
			)
			(layer "F.Fab")
		)
		(fp_line
			(start 0.12065 -0.3048)
			(end 0.67945 -0.3048)
			(stroke
				(width 0.1)
				(type default)
			)
			(layer "F.Fab")
		)
		(fp_line
			(start 0.12065 -0.2794)
			(end 0.12065 -0.3048)
			(stroke
				(width 0.1)
				(type default)
			)
			(layer "F.Fab")
		)
		(fp_line
			(start 0.67945 -0.3048)
			(end 0.67945 0.3048)
			(stroke
				(width 0.1)
				(type default)
			)
			(layer "F.Fab")
		)
		(fp_line
			(start 0.67945 0.3048)
			(end 0.120396 0.3048)
			(stroke
				(width 0.1)
				(type default)
			)
			(layer "F.Fab")
		)
		(pad "1" smd circle
			(at -0.40005 0)
			(size 0 0)
			(layers "F.Cu" "F.Mask" "F.Paste")
			(net "GND")
		)
		(pad "2" smd circle
			(at 0.40005 0)
			(size 0 0)
			(layers "F.Cu" "F.Mask" "F.Paste")
			(net "JTAG_BMC_OE")
		)
	)
	(footprint ""
		(layer "F.Cu")
		(at 48.478694 -32.277558 90)
		(property "Reference" "C1825"
			(at 0 0 90)
			(layer "F.SilkS")
			(hide yes)
			(effects
				(font
					(size 1.27 1.27)
				)
			)
		)
		(property "Value" ""
			(at 0 0 90)
			(layer "F.Fab")
			(effects
				(font
					(size 1.27 1.27)
				)
			)
		)
		(duplicate_pad_numbers_are_jumpers no)
		(fp_line
			(start 0.7874 -0.4064)
			(end 0.7874 0.4064)
			(stroke
				(width 0.1524)
				(type default)
			)
			(layer "F.SilkS")
		)
		(fp_line
			(start -0.7874 -0.4064)
			(end 0.7874 -0.4064)
			(stroke
				(width 0.1524)
				(type default)
			)
			(layer "F.SilkS")
		)
		(fp_line
			(start 0.7874 0.4064)
			(end -0.7874 0.4064)
			(stroke
				(width 0.1524)
				(type default)
			)
			(layer "F.SilkS")
		)
		(fp_line
			(start -0.7874 0.4064)
			(end -0.7874 -0.4064)
			(stroke
				(width 0.1524)
				(type default)
			)
			(layer "F.SilkS")
		)
		(fp_line
			(start -0.12065 -0.305054)
			(end -0.12065 -0.2794)
			(stroke
				(width 0.1)
				(type default)
			)
			(layer "F.Fab")
		)
		(fp_line
			(start -0.67945 -0.305054)
			(end -0.12065 -0.305054)
			(stroke
				(width 0.1)
				(type default)
			)
			(layer "F.Fab")
		)
		(fp_line
			(start 0.67945 -0.3048)
			(end 0.67945 0.3048)
			(stroke
				(width 0.1)
				(type default)
			)
			(layer "F.Fab")
		)
		(fp_line
			(start 0.12065 -0.3048)
			(end 0.67945 -0.3048)
			(stroke
				(width 0.1)
				(type default)
			)
			(layer "F.Fab")
		)
		(fp_line
			(start 0.12065 -0.2794)
			(end 0.12065 -0.3048)
			(stroke
				(width 0.1)
				(type default)
			)
			(layer "F.Fab")
		)
		(fp_line
			(start -0.12065 -0.2794)
			(end 0.12065 -0.2794)
			(stroke
				(width 0.1)
				(type default)
			)
			(layer "F.Fab")
		)
		(fp_line
			(start 0.120396 0.2794)
			(end -0.12065 0.2794)
			(stroke
				(width 0.1)
				(type default)
			)
			(layer "F.Fab")
		)
		(fp_line
			(start -0.12065 0.2794)
			(end -0.12065 0.3048)
			(stroke
				(width 0.1)
				(type default)
			)
			(layer "F.Fab")
		)
		(fp_line
			(start 0.67945 0.3048)
			(end 0.120396 0.3048)
			(stroke
				(width 0.1)
				(type default)
			)
			(layer "F.Fab")
		)
		(fp_line
			(start 0.120396 0.3048)
			(end 0.120396 0.2794)
			(stroke
				(width 0.1)
				(type default)
			)
			(layer "F.Fab")
		)
		(fp_line
			(start -0.12065 0.3048)
			(end -0.67945 0.3048)
			(stroke
				(width 0.1)
				(type default)
			)
			(layer "F.Fab")
		)
		(fp_line
			(start -0.67945 0.3048)
			(end -0.67945 -0.305054)
			(stroke
				(width 0.1)
				(type default)
			)
			(layer "F.Fab")
		)
		(pad "1" smd circle
			(at -0.40005 0 90)
			(size 0 0)
			(layers "F.Cu" "F.Mask" "F.Paste")
			(net "P3V3_AUX")
		)
		(pad "2" smd circle
			(at 0.40005 0 90)
			(size 0 0)
			(layers "F.Cu" "F.Mask" "F.Paste")
			(net "GND")
		)
	)
)
